(kicad_pcb
	(version 20260206)
	(generator "pcbnew")
	(generator_version "10.0")
	(general
		(thickness 1.6)
		(legacy_teardrops no)
	)
	(paper "A4")
	(title_block
		(title "04192023_DAF0TMB3IC0_F0TG_MB_C_brd_V02_OCP.brd")
		(comment 1 "Grand Teton / footprints 2655-2661 of 8354")
	)
	(layers
		(0 "F.Cu" signal "TOP")
		(4 "In1.Cu" signal "GND")
		(6 "In2.Cu" signal "IN1")
		(8 "In3.Cu" signal "GND1")
		(10 "In4.Cu" signal "IN2")
		(12 "In5.Cu" signal "GND2")
		(14 "In6.Cu" signal "IN3")
		(16 "In7.Cu" signal "GND3")
		(18 "In8.Cu" signal "VCC")
		(20 "In9.Cu" signal "VCC1")
		(22 "In10.Cu" signal "GND4")
		(24 "In11.Cu" signal "IN4")
		(26 "In12.Cu" signal "GND5")
		(28 "In13.Cu" signal "IN5")
		(30 "In14.Cu" signal "GND6")
		(32 "In15.Cu" signal "IN6")
		(34 "In16.Cu" signal "GND7")
		(2 "B.Cu" signal "BOTTOM")
		(9 "F.Adhes" user "F.Adhesive")
		(11 "B.Adhes" user "B.Adhesive")
		(13 "F.Paste" user "Package Geometry/Pastemask Top")
		(15 "B.Paste" user "Package Geometry/Pastemask Bottom")
		(5 "F.SilkS" user "Ref Des/Silkscreen Top")
		(7 "B.SilkS" user "Ref Des/Silkscreen Bottom")
		(1 "F.Mask" user "Board Geometry/Soldermask Top")
		(3 "B.Mask" user "Board Geometry/Soldermask Bottom")
		(17 "Dwgs.User" user "User.Drawings")
		(19 "Cmts.User" user "User.Comments")
		(21 "Eco1.User" user "User.Eco1")
		(23 "Eco2.User" user "User.Eco2")
		(25 "Edge.Cuts" user "Board Geometry/Outline")
		(27 "Margin" user)
		(31 "F.CrtYd" user "Package Geometry/Place Bound Top")
		(29 "B.CrtYd" user "Package Geometry/Place Bound Bottom")
		(35 "F.Fab" user "Ref Des/Assembly Top")
		(33 "B.Fab" user "Ref Des/Assembly Bottom")
	)
	(footprint ""
		(layer "F.Cu")
		(at 395.269212 -321.148202 90)
		(property "Reference" "R581"
			(at 0 0 90)
			(layer "F.SilkS")
			(hide yes)
			(effects
				(font
					(size 1.27 1.27)
				)
			)
		)
		(property "Value" ""
			(at 0 0 90)
			(layer "F.Fab")
			(effects
				(font
					(size 1.27 1.27)
				)
			)
		)
		(duplicate_pad_numbers_are_jumpers no)
		(fp_line
			(start 0.7874 -0.4064)
			(end 0.7874 0.4064)
			(stroke
				(width 0.1524)
				(type default)
			)
			(layer "F.SilkS")
		)
		(fp_line
			(start -0.7874 -0.4064)
			(end 0.7874 -0.4064)
			(stroke
				(width 0.1524)
				(type default)
			)
			(layer "F.SilkS")
		)
		(fp_line
			(start 0.7874 0.4064)
			(end -0.7874 0.4064)
			(stroke
				(width 0.1524)
				(type default)
			)
			(layer "F.SilkS")
		)
		(fp_line
			(start -0.7874 0.4064)
			(end -0.7874 -0.4064)
			(stroke
				(width 0.1524)
				(type default)
			)
			(layer "F.SilkS")
		)
		(fp_line
			(start -0.12065 -0.305054)
			(end -0.12065 -0.2794)
			(stroke
				(width 0.1)
				(type default)
			)
			(layer "F.Fab")
		)
		(fp_line
			(start -0.67945 -0.305054)
			(end -0.12065 -0.305054)
			(stroke
				(width 0.1)
				(type default)
			)
			(layer "F.Fab")
		)
		(fp_line
			(start 0.67945 -0.3048)
			(end 0.67945 0.3048)
			(stroke
				(width 0.1)
				(type default)
			)
			(layer "F.Fab")
		)
		(fp_line
			(start 0.12065 -0.3048)
			(end 0.67945 -0.3048)
			(stroke
				(width 0.1)
				(type default)
			)
			(layer "F.Fab")
		)
		(fp_line
			(start 0.12065 -0.2794)
			(end 0.12065 -0.3048)
			(stroke
				(width 0.1)
				(type default)
			)
			(layer "F.Fab")
		)
		(fp_line
			(start -0.12065 -0.2794)
			(end 0.12065 -0.2794)
			(stroke
				(width 0.1)
				(type default)
			)
			(layer "F.Fab")
		)
		(fp_line
			(start 0.120396 0.2794)
			(end -0.12065 0.2794)
			(stroke
				(width 0.1)
				(type default)
			)
			(layer "F.Fab")
		)
		(fp_line
			(start -0.12065 0.2794)
			(end -0.12065 0.3048)
			(stroke
				(width 0.1)
				(type default)
			)
			(layer "F.Fab")
		)
		(fp_line
			(start 0.67945 0.3048)
			(end 0.120396 0.3048)
			(stroke
				(width 0.1)
				(type default)
			)
			(layer "F.Fab")
		)
		(fp_line
			(start 0.120396 0.3048)
			(end 0.120396 0.2794)
			(stroke
				(width 0.1)
				(type default)
			)
			(layer "F.Fab")
		)
		(fp_line
			(start -0.12065 0.3048)
			(end -0.67945 0.3048)
			(stroke
				(width 0.1)
				(type default)
			)
			(layer "F.Fab")
		)
		(fp_line
			(start -0.67945 0.3048)
			(end -0.67945 -0.305054)
			(stroke
				(width 0.1)
				(type default)
			)
			(layer "F.Fab")
		)
		(pad "1" smd circle
			(at -0.40005 0 90)
			(size 0 0)
			(layers "F.Cu" "F.Mask" "F.Paste")
			(net "RST_CPU0_RSMRST_N")
		)
		(pad "2" smd circle
			(at 0.40005 0 90)
			(size 0 0)
			(layers "F.Cu" "F.Mask" "F.Paste")
			(net "PVDD18_S5_P0")
		)
	)
	(footprint ""
		(layer "F.Cu")
		(at 384.036062 -416.899344 -90)
		(property "Reference" "C6573"
			(at 0 0 270)
			(layer "F.SilkS")
			(hide yes)
			(effects
				(font
					(size 1.27 1.27)
				)
			)
		)
		(property "Value" ""
			(at 0 0 270)
			(layer "F.Fab")
			(effects
				(font
					(size 1.27 1.27)
				)
			)
		)
		(duplicate_pad_numbers_are_jumpers no)
		(fp_line
			(start -0.299974 0.150114)
			(end -0.299974 -0.150114)
			(stroke
				(width 0.1)
				(type default)
			)
			(layer "F.Fab")
		)
		(fp_line
			(start 0.299974 0.150114)
			(end -0.299974 0.150114)
			(stroke
				(width 0.1)
				(type default)
			)
			(layer "F.Fab")
		)
		(fp_line
			(start -0.299974 -0.150114)
			(end 0.299974 -0.150114)
			(stroke
				(width 0.1)
				(type default)
			)
			(layer "F.Fab")
		)
		(fp_line
			(start 0.299974 -0.150114)
			(end 0.299974 0.150114)
			(stroke
				(width 0.1)
				(type default)
			)
			(layer "F.Fab")
		)
		(pad "1" smd rect
			(at -0.2667 0 270)
			(size 0.3048 0.381)
			(layers "F.Cu" "F.Mask" "F.Paste")
			(net "P5E_CPU0_P2_TX_BUF_C_DP<4>")
		)
		(pad "2" smd rect
			(at 0.2667 0 270)
			(size 0.3048 0.381)
			(layers "F.Cu" "F.Mask" "F.Paste")
			(net "P5E_CPU0_P2_TX_BUF_DP<4>")
		)
	)
	(footprint ""
		(layer "F.Cu")
		(at 432.308 -405.13)
		(property "Reference" "R1477"
			(at 0 0 0)
			(layer "F.SilkS")
			(hide yes)
			(effects
				(font
					(size 1.27 1.27)
				)
			)
		)
		(property "Value" ""
			(at 0 0 0)
			(layer "F.Fab")
			(effects
				(font
					(size 1.27 1.27)
				)
			)
		)
		(duplicate_pad_numbers_are_jumpers no)
		(fp_line
			(start -0.32512 -0.175006)
			(end 0.32512 -0.175006)
			(stroke
				(width 0.1)
				(type default)
			)
			(layer "F.Fab")
		)
		(fp_line
			(start -0.32512 0.175006)
			(end -0.32512 -0.175006)
			(stroke
				(width 0.1)
				(type default)
			)
			(layer "F.Fab")
		)
		(fp_line
			(start 0.32512 -0.175006)
			(end 0.32512 0.175006)
			(stroke
				(width 0.1)
				(type default)
			)
			(layer "F.Fab")
		)
		(fp_line
			(start 0.32512 0.175006)
			(end -0.32512 0.175006)
			(stroke
				(width 0.1)
				(type default)
			)
			(layer "F.Fab")
		)
		(pad "1" smd rect
			(at -0.2667 0)
			(size 0.3048 0.381)
			(layers "F.Cu" "F.Mask" "F.Paste")
			(net "P1V8_CPU0_RT_1D")
		)
		(pad "2" smd rect
			(at 0.2667 0 180)
			(size 0.3048 0.381)
			(layers "F.Cu" "F.Mask" "F.Paste")
			(net "JTAG_TMS_RT_CPU0_P2")
		)
	)
	(footprint ""
		(layer "F.Cu")
		(at 364.362238 -412.370016 180)
		(property "Reference" "C9000"
			(at 0 0 180)
			(layer "F.SilkS")
			(hide yes)
			(effects
				(font
					(size 1.27 1.27)
				)
			)
		)
		(property "Value" ""
			(at 0 0 180)
			(layer "F.Fab")
			(effects
				(font
					(size 1.27 1.27)
				)
			)
		)
		(duplicate_pad_numbers_are_jumpers no)
		(fp_line
			(start 0.7874 0.4064)
			(end -0.7874 0.4064)
			(stroke
				(width 0.1524)
				(type default)
			)
			(layer "F.SilkS")
		)
		(fp_line
			(start 0.7874 -0.4064)
			(end 0.7874 0.4064)
			(stroke
				(width 0.1524)
				(type default)
			)
			(layer "F.SilkS")
		)
		(fp_line
			(start -0.7874 0.4064)
			(end -0.7874 -0.4064)
			(stroke
				(width 0.1524)
				(type default)
			)
			(layer "F.SilkS")
		)
		(fp_line
			(start -0.7874 -0.4064)
			(end 0.7874 -0.4064)
			(stroke
				(width 0.1524)
				(type default)
			)
			(layer "F.SilkS")
		)
		(fp_line
			(start 0.67945 0.3048)
			(end 0.120396 0.3048)
			(stroke
				(width 0.1)
				(type default)
			)
			(layer "F.Fab")
		)
		(fp_line
			(start 0.67945 -0.3048)
			(end 0.67945 0.3048)
			(stroke
				(width 0.1)
				(type default)
			)
			(layer "F.Fab")
		)
		(fp_line
			(start 0.12065 -0.2794)
			(end 0.12065 -0.3048)
			(stroke
				(width 0.1)
				(type default)
			)
			(layer "F.Fab")
		)
		(fp_line
			(start 0.12065 -0.3048)
			(end 0.67945 -0.3048)
			(stroke
				(width 0.1)
				(type default)
			)
			(layer "F.Fab")
		)
		(fp_line
			(start 0.120396 0.3048)
			(end 0.120396 0.2794)
			(stroke
				(width 0.1)
				(type default)
			)
			(layer "F.Fab")
		)
		(fp_line
			(start 0.120396 0.2794)
			(end -0.12065 0.2794)
			(stroke
				(width 0.1)
				(type default)
			)
			(layer "F.Fab")
		)
		(fp_line
			(start -0.12065 0.3048)
			(end -0.67945 0.3048)
			(stroke
				(width 0.1)
				(type default)
			)
			(layer "F.Fab")
		)
		(fp_line
			(start -0.12065 0.2794)
			(end -0.12065 0.3048)
			(stroke
				(width 0.1)
				(type default)
			)
			(layer "F.Fab")
		)
		(fp_line
			(start -0.12065 -0.2794)
			(end 0.12065 -0.2794)
			(stroke
				(width 0.1)
				(type default)
			)
			(layer "F.Fab")
		)
		(fp_line
			(start -0.12065 -0.305054)
			(end -0.12065 -0.2794)
			(stroke
				(width 0.1)
				(type default)
			)
			(layer "F.Fab")
		)
		(fp_line
			(start -0.67945 0.3048)
			(end -0.67945 -0.305054)
			(stroke
				(width 0.1)
				(type default)
			)
			(layer "F.Fab")
		)
		(fp_line
			(start -0.67945 -0.305054)
			(end -0.12065 -0.305054)
			(stroke
				(width 0.1)
				(type default)
			)
			(layer "F.Fab")
		)
		(pad "1" smd circle
			(at -0.40005 0 180)
			(size 0 0)
			(layers "F.Cu" "F.Mask" "F.Paste")
			(net "PRSNT_CABLE_SWB_B1_ISO_N")
		)
		(pad "2" smd circle
			(at 0.40005 0 180)
			(size 0 0)
			(layers "F.Cu" "F.Mask" "F.Paste")
			(net "GND")
		)
	)
	(footprint ""
		(layer "F.Cu")
		(at 103.520494 -386.44068 90)
		(property "Reference" "C110"
			(at 0 0 90)
			(layer "F.SilkS")
			(hide yes)
			(effects
				(font
					(size 1.27 1.27)
				)
			)
		)
		(property "Value" ""
			(at 0 0 90)
			(layer "F.Fab")
			(effects
				(font
					(size 1.27 1.27)
				)
			)
		)
		(duplicate_pad_numbers_are_jumpers no)
		(fp_line
			(start 0.7874 -0.4064)
			(end 0.7874 0.4064)
			(stroke
				(width 0.1524)
				(type default)
			)
			(layer "F.SilkS")
		)
		(fp_line
			(start -0.7874 -0.4064)
			(end 0.7874 -0.4064)
			(stroke
				(width 0.1524)
				(type default)
			)
			(layer "F.SilkS")
		)
		(fp_line
			(start 0.7874 0.4064)
			(end -0.7874 0.4064)
			(stroke
				(width 0.1524)
				(type default)
			)
			(layer "F.SilkS")
		)
		(fp_line
			(start -0.7874 0.4064)
			(end -0.7874 -0.4064)
			(stroke
				(width 0.1524)
				(type default)
			)
			(layer "F.SilkS")
		)
		(fp_line
			(start -0.12065 -0.305054)
			(end -0.12065 -0.2794)
			(stroke
				(width 0.1)
				(type default)
			)
			(layer "F.Fab")
		)
		(fp_line
			(start -0.67945 -0.305054)
			(end -0.12065 -0.305054)
			(stroke
				(width 0.1)
				(type default)
			)
			(layer "F.Fab")
		)
		(fp_line
			(start 0.67945 -0.3048)
			(end 0.67945 0.3048)
			(stroke
				(width 0.1)
				(type default)
			)
			(layer "F.Fab")
		)
		(fp_line
			(start 0.12065 -0.3048)
			(end 0.67945 -0.3048)
			(stroke
				(width 0.1)
				(type default)
			)
			(layer "F.Fab")
		)
		(fp_line
			(start 0.12065 -0.2794)
			(end 0.12065 -0.3048)
			(stroke
				(width 0.1)
				(type default)
			)
			(layer "F.Fab")
		)
		(fp_line
			(start -0.12065 -0.2794)
			(end 0.12065 -0.2794)
			(stroke
				(width 0.1)
				(type default)
			)
			(layer "F.Fab")
		)
		(fp_line
			(start 0.120396 0.2794)
			(end -0.12065 0.2794)
			(stroke
				(width 0.1)
				(type default)
			)
			(layer "F.Fab")
		)
		(fp_line
			(start -0.12065 0.2794)
			(end -0.12065 0.3048)
			(stroke
				(width 0.1)
				(type default)
			)
			(layer "F.Fab")
		)
		(fp_line
			(start 0.67945 0.3048)
			(end 0.120396 0.3048)
			(stroke
				(width 0.1)
				(type default)
			)
			(layer "F.Fab")
		)
		(fp_line
			(start 0.120396 0.3048)
			(end 0.120396 0.2794)
			(stroke
				(width 0.1)
				(type default)
			)
			(layer "F.Fab")
		)
		(fp_line
			(start -0.12065 0.3048)
			(end -0.67945 0.3048)
			(stroke
				(width 0.1)
				(type default)
			)
			(layer "F.Fab")
		)
		(fp_line
			(start -0.67945 0.3048)
			(end -0.67945 -0.305054)
			(stroke
				(width 0.1)
				(type default)
			)
			(layer "F.Fab")
		)
		(pad "1" smd circle
			(at -0.40005 0 90)
			(size 0 0)
			(layers "F.Cu" "F.Mask" "F.Paste")
			(net "P1V8_CPU1_RT_1D")
		)
		(pad "2" smd circle
			(at 0.40005 0 90)
			(size 0 0)
			(layers "F.Cu" "F.Mask" "F.Paste")
			(net "GND")
		)
	)
	(footprint ""
		(layer "F.Cu")
		(at 105.84561 -64.55791 180)
		(property "Reference" "R6221"
			(at 0 0 180)
			(layer "F.SilkS")
			(hide yes)
			(effects
				(font
					(size 1.27 1.27)
				)
			)
		)
		(property "Value" ""
			(at 0 0 180)
			(layer "F.Fab")
			(effects
				(font
					(size 1.27 1.27)
				)
			)
		)
		(duplicate_pad_numbers_are_jumpers no)
		(fp_line
			(start 0.7874 0.4064)
			(end -0.7874 0.4064)
			(stroke
				(width 0.1524)
				(type default)
			)
			(layer "F.SilkS")
		)
		(fp_line
			(start 0.7874 -0.4064)
			(end 0.7874 0.4064)
			(stroke
				(width 0.1524)
				(type default)
			)
			(layer "F.SilkS")
		)
		(fp_line
			(start -0.7874 0.4064)
			(end -0.7874 -0.4064)
			(stroke
				(width 0.1524)
				(type default)
			)
			(layer "F.SilkS")
		)
		(fp_line
			(start -0.7874 -0.4064)
			(end 0.7874 -0.4064)
			(stroke
				(width 0.1524)
				(type default)
			)
			(layer "F.SilkS")
		)
		(fp_line
			(start 0.67945 0.3048)
			(end 0.120396 0.3048)
			(stroke
				(width 0.1)
				(type default)
			)
			(layer "F.Fab")
		)
		(fp_line
			(start 0.67945 -0.3048)
			(end 0.67945 0.3048)
			(stroke
				(width 0.1)
				(type default)
			)
			(layer "F.Fab")
		)
		(fp_line
			(start 0.12065 -0.2794)
			(end 0.12065 -0.3048)
			(stroke
				(width 0.1)
				(type default)
			)
			(layer "F.Fab")
		)
		(fp_line
			(start 0.12065 -0.3048)
			(end 0.67945 -0.3048)
			(stroke
				(width 0.1)
				(type default)
			)
			(layer "F.Fab")
		)
		(fp_line
			(start 0.120396 0.3048)
			(end 0.120396 0.2794)
			(stroke
				(width 0.1)
				(type default)
			)
			(layer "F.Fab")
		)
		(fp_line
			(start 0.120396 0.2794)
			(end -0.12065 0.2794)
			(stroke
				(width 0.1)
				(type default)
			)
			(layer "F.Fab")
		)
		(fp_line
			(start -0.12065 0.3048)
			(end -0.67945 0.3048)
			(stroke
				(width 0.1)
				(type default)
			)
			(layer "F.Fab")
		)
		(fp_line
			(start -0.12065 0.2794)
			(end -0.12065 0.3048)
			(stroke
				(width 0.1)
				(type default)
			)
			(layer "F.Fab")
		)
		(fp_line
			(start -0.12065 -0.2794)
			(end 0.12065 -0.2794)
			(stroke
				(width 0.1)
				(type default)
			)
			(layer "F.Fab")
		)
		(fp_line
			(start -0.12065 -0.305054)
			(end -0.12065 -0.2794)
			(stroke
				(width 0.1)
				(type default)
			)
			(layer "F.Fab")
		)
		(fp_line
			(start -0.67945 0.3048)
			(end -0.67945 -0.305054)
			(stroke
				(width 0.1)
				(type default)
			)
			(layer "F.Fab")
		)
		(fp_line
			(start -0.67945 -0.305054)
			(end -0.12065 -0.305054)
			(stroke
				(width 0.1)
				(type default)
			)
			(layer "F.Fab")
		)
		(pad "1" smd circle
			(at -0.40005 0 180)
			(size 0 0)
			(layers "F.Cu" "F.Mask" "F.Paste")
			(net "USB_CPU0_ADD_A2")
		)
		(pad "2" smd circle
			(at 0.40005 0 180)
			(size 0 0)
			(layers "F.Cu" "F.Mask" "F.Paste")
			(net "GND")
		)
	)
	(footprint ""
		(layer "F.Cu")
		(at 387.431026 -51.1175)
		(property "Reference" "C604"
			(at 0 0 0)
			(layer "F.SilkS")
			(hide yes)
			(effects
				(font
					(size 1.27 1.27)
				)
			)
		)
		(property "Value" ""
			(at 0 0 0)
			(layer "F.Fab")
			(effects
				(font
					(size 1.27 1.27)
				)
			)
		)
		(duplicate_pad_numbers_are_jumpers no)
		(fp_line
			(start -0.7874 -0.4064)
			(end 0.7874 -0.4064)
			(stroke
				(width 0.1524)
				(type default)
			)
			(layer "F.SilkS")
		)
		(fp_line
			(start -0.7874 0.4064)
			(end -0.7874 -0.4064)
			(stroke
				(width 0.1524)
				(type default)
			)
			(layer "F.SilkS")
		)
		(fp_line
			(start 0.7874 -0.4064)
			(end 0.7874 0.4064)
			(stroke
				(width 0.1524)
				(type default)
			)
			(layer "F.SilkS")
		)
		(fp_line
			(start 0.7874 0.4064)
			(end -0.7874 0.4064)
			(stroke
				(width 0.1524)
				(type default)
			)
			(layer "F.SilkS")
		)
		(fp_line
			(start -0.67945 -0.305054)
			(end -0.12065 -0.305054)
			(stroke
				(width 0.1)
				(type default)
			)
			(layer "F.Fab")
		)
		(fp_line
			(start -0.67945 0.3048)
			(end -0.67945 -0.305054)
			(stroke
				(width 0.1)
				(type default)
			)
			(layer "F.Fab")
		)
		(fp_line
			(start -0.12065 -0.305054)
			(end -0.12065 -0.2794)
			(stroke
				(width 0.1)
				(type default)
			)
			(layer "F.Fab")
		)
		(fp_line
			(start -0.12065 -0.2794)
			(end 0.12065 -0.2794)
			(stroke
				(width 0.1)
				(type default)
			)
			(layer "F.Fab")
		)
		(fp_line
			(start -0.12065 0.2794)
			(end -0.12065 0.3048)
			(stroke
				(width 0.1)
				(type default)
			)
			(layer "F.Fab")
		)
		(fp_line
			(start -0.12065 0.3048)
			(end -0.67945 0.3048)
			(stroke
				(width 0.1)
				(type default)
			)
			(layer "F.Fab")
		)
		(fp_line
			(start 0.120396 0.2794)
			(end -0.12065 0.2794)
			(stroke
				(width 0.1)
				(type default)
			)
			(layer "F.Fab")
		)
		(fp_line
			(start 0.120396 0.3048)
			(end 0.120396 0.2794)
			(stroke
				(width 0.1)
				(type default)
			)
			(layer "F.Fab")
		)
		(fp_line
			(start 0.12065 -0.3048)
			(end 0.67945 -0.3048)
			(stroke
				(width 0.1)
				(type default)
			)
			(layer "F.Fab")
		)
		(fp_line
			(start 0.12065 -0.2794)
			(end 0.12065 -0.3048)
			(stroke
				(width 0.1)
				(type default)
			)
			(layer "F.Fab")
		)
		(fp_line
			(start 0.67945 -0.3048)
			(end 0.67945 0.3048)
			(stroke
				(width 0.1)
				(type default)
			)
			(layer "F.Fab")
		)
		(fp_line
			(start 0.67945 0.3048)
			(end 0.120396 0.3048)
			(stroke
				(width 0.1)
				(type default)
			)
			(layer "F.Fab")
		)
		(pad "1" smd circle
			(at -0.40005 0)
			(size 0 0)
			(layers "F.Cu" "F.Mask" "F.Paste")
			(net "HDT_HDR_TCK")
		)
		(pad "2" smd circle
			(at 0.40005 0)
			(size 0 0)
			(layers "F.Cu" "F.Mask" "F.Paste")
			(net "GND")
		)
	)
)
